(kicad_pcb
	(version 20260206)
	(generator "pcbnew")
	(generator_version "10.0")
	(general
		(thickness 1.6)
		(legacy_teardrops no)
	)
	(paper "A4")
	(title_block
		(title "Bryce Canyon_SCC_16316-1_OCP.brd")
		(comment 1 "Bryce Canyon / footprints 727-733 of 1561")
	)
	(layers
		(0 "F.Cu" signal "TOP")
		(4 "In1.Cu" signal "L2GND")
		(6 "In2.Cu" signal "L3")
		(8 "In3.Cu" signal "L4VCC")
		(10 "In4.Cu" signal "L5VCC")
		(12 "In5.Cu" signal "L6")
		(14 "In6.Cu" signal "L7GND")
		(2 "B.Cu" signal "BOTTOM")
		(9 "F.Adhes" user "F.Adhesive")
		(11 "B.Adhes" user "B.Adhesive")
		(13 "F.Paste" user "Package Geometry/Pastemask Top")
		(15 "B.Paste" user "Package Geometry/Pastemask Bottom")
		(5 "F.SilkS" user "Ref Des/Silkscreen Top")
		(7 "B.SilkS" user "Ref Des/Silkscreen Bottom")
		(1 "F.Mask" user "Board Geometry/Soldermask Top")
		(3 "B.Mask" user "Board Geometry/Soldermask Bottom")
		(17 "Dwgs.User" user "User.Drawings")
		(19 "Cmts.User" user "User.Comments")
		(21 "Eco1.User" user "User.Eco1")
		(23 "Eco2.User" user "User.Eco2")
		(25 "Edge.Cuts" user "Board Geometry/Outline")
		(27 "Margin" user)
		(31 "F.CrtYd" user "Package Geometry/Place Bound Top")
		(29 "B.CrtYd" user "Package Geometry/Place Bound Bottom")
		(35 "F.Fab" user "Ref Des/Assembly Top")
		(33 "B.Fab" user "Ref Des/Assembly Bottom")
	)
	(footprint ""
		(layer "F.Cu")
		(at 59.6392 -72.6694)
		(property "Reference" "R424"
			(at 0 0 0)
			(layer "F.SilkS")
			(hide yes)
			(effects
				(font
					(size 1.27 1.27)
				)
			)
		)
		(property "Value" "0R2J-2-GP"
			(at 0.064008 -3.993896 0)
			(unlocked yes)
			(layer "F.Fab")
			(hide yes)
			(effects
				(font
					(size 1.016 1.016)
					(thickness 0.1524)
				)
			)
		)
		(property "Device Type" "R402H16"
			(at 0.064008 -5.517896 0)
			(unlocked yes)
			(layer "F.Fab")
			(hide yes)
			(effects
				(font
					(size 1.016 1.016)
					(thickness 0.1524)
				)
			)
		)
		(duplicate_pad_numbers_are_jumpers no)
		(fp_line
			(start -0.508 -0.9398)
			(end -0.508 0.9398)
			(stroke
				(width 0.1524)
				(type default)
			)
			(layer "F.SilkS")
		)
		(fp_line
			(start 0.508 -0.9398)
			(end -0.508 -0.9398)
			(stroke
				(width 0.1524)
				(type default)
			)
			(layer "F.SilkS")
		)
		(fp_rect
			(start -0.508 0.9398)
			(end 0.508 -0.9398)
			(stroke
				(width 0)
				(type default)
			)
			(fill no)
			(layer "F.CrtYd")
		)
		(fp_rect
			(start -0.508 0.9398)
			(end 0.508 -0.9398)
			(stroke
				(width 0)
				(type default)
			)
			(fill no)
			(layer "F.Fab")
		)
		(pad "1" smd custom
			(at 0 -0.4445)
			(size 0.1397 0.1397)
			(layers "F.Cu" "F.Mask" "F.Paste")
			(net "LS_EN_U37")
			(options
				(clearance outline)
				(anchor circle)
			)
			(primitives
				(gr_poly
					(pts
						(arc
							(start -0.1778 -0.2794)
							(mid -0.249642 -0.249642)
							(end -0.2794 -0.1778)
						)
						(arc
							(start -0.2794 0.1778)
							(mid -0.249642 0.249642)
							(end -0.1778 0.2794)
						)
						(arc
							(start 0.1778 0.2794)
							(mid 0.249642 0.249642)
							(end 0.2794 0.1778)
						)
						(arc
							(start 0.2794 -0.1778)
							(mid 0.249642 -0.249642)
							(end 0.1778 -0.2794)
						)
					)
					(width 0)
					(fill yes)
				)
			)
		)
		(pad "2" smd custom
			(at 0 0.4445)
			(size 0.1397 0.1397)
			(layers "F.Cu" "F.Mask" "F.Paste")
			(net "VREF4")
			(options
				(clearance outline)
				(anchor circle)
			)
			(primitives
				(gr_poly
					(pts
						(arc
							(start -0.1778 -0.2794)
							(mid -0.249642 -0.249642)
							(end -0.2794 -0.1778)
						)
						(arc
							(start -0.2794 0.1778)
							(mid -0.249642 0.249642)
							(end -0.1778 0.2794)
						)
						(arc
							(start 0.1778 0.2794)
							(mid 0.249642 0.249642)
							(end 0.2794 0.1778)
						)
						(arc
							(start 0.2794 -0.1778)
							(mid 0.249642 -0.249642)
							(end 0.1778 -0.2794)
						)
					)
					(width 0)
					(fill yes)
				)
			)
		)
	)
	(footprint ""
		(layer "F.Cu")
		(at 71.882 -103.505 180)
		(property "Reference" "R513"
			(at 0 0 180)
			(layer "F.SilkS")
			(hide yes)
			(effects
				(font
					(size 1.27 1.27)
				)
			)
		)
		(property "Value" "44K2R2F-1-GP"
			(at 0.064008 -3.993896 180)
			(unlocked yes)
			(layer "F.Fab")
			(hide yes)
			(effects
				(font
					(size 1.016 1.016)
					(thickness 0.1524)
				)
			)
		)
		(property "Device Type" "R402H16"
			(at 0.064008 -5.517896 180)
			(unlocked yes)
			(layer "F.Fab")
			(hide yes)
			(effects
				(font
					(size 1.016 1.016)
					(thickness 0.1524)
				)
			)
		)
		(duplicate_pad_numbers_are_jumpers no)
		(fp_line
			(start 0.508 -0.9398)
			(end -0.508 -0.9398)
			(stroke
				(width 0.1524)
				(type default)
			)
			(layer "F.SilkS")
		)
		(fp_line
			(start -0.508 -0.9398)
			(end -0.508 0.9398)
			(stroke
				(width 0.1524)
				(type default)
			)
			(layer "F.SilkS")
		)
		(fp_rect
			(start -0.508 0.9398)
			(end 0.508 -0.9398)
			(stroke
				(width 0)
				(type default)
			)
			(fill no)
			(layer "F.CrtYd")
		)
		(fp_rect
			(start -0.508 0.9398)
			(end 0.508 -0.9398)
			(stroke
				(width 0)
				(type default)
			)
			(fill no)
			(layer "F.Fab")
		)
		(pad "1" smd custom
			(at 0 -0.4445 180)
			(size 0.1397 0.1397)
			(layers "F.Cu" "F.Mask" "F.Paste")
			(net "P3V3_VFB")
			(options
				(clearance outline)
				(anchor circle)
			)
			(primitives
				(gr_poly
					(pts
						(arc
							(start -0.1778 -0.2794)
							(mid -0.249642 -0.249642)
							(end -0.2794 -0.1778)
						)
						(arc
							(start -0.2794 0.1778)
							(mid -0.249642 0.249642)
							(end -0.1778 0.2794)
						)
						(arc
							(start 0.1778 0.2794)
							(mid 0.249642 0.249642)
							(end 0.2794 0.1778)
						)
						(arc
							(start 0.2794 -0.1778)
							(mid 0.249642 -0.249642)
							(end 0.1778 -0.2794)
						)
					)
					(width 0)
					(fill yes)
				)
			)
		)
		(pad "2" smd custom
			(at 0 0.4445 180)
			(size 0.1397 0.1397)
			(layers "F.Cu" "F.Mask" "F.Paste")
			(net "P3V3_VFB_R")
			(options
				(clearance outline)
				(anchor circle)
			)
			(primitives
				(gr_poly
					(pts
						(arc
							(start -0.1778 -0.2794)
							(mid -0.249642 -0.249642)
							(end -0.2794 -0.1778)
						)
						(arc
							(start -0.2794 0.1778)
							(mid -0.249642 0.249642)
							(end -0.1778 0.2794)
						)
						(arc
							(start 0.1778 0.2794)
							(mid 0.249642 0.249642)
							(end 0.2794 0.1778)
						)
						(arc
							(start 0.2794 -0.1778)
							(mid 0.249642 -0.249642)
							(end 0.1778 -0.2794)
						)
					)
					(width 0)
					(fill yes)
				)
			)
		)
	)
	(footprint ""
		(layer "F.Cu")
		(at 191.902842 -23.32101 180)
		(property "Reference" "R259"
			(at 0 0 180)
			(layer "F.SilkS")
			(hide yes)
			(effects
				(font
					(size 1.27 1.27)
				)
			)
		)
		(property "Value" "4K7R2F-GP"
			(at 0.064008 -3.993896 180)
			(unlocked yes)
			(layer "F.Fab")
			(hide yes)
			(effects
				(font
					(size 1.016 1.016)
					(thickness 0.1524)
				)
			)
		)
		(property "Device Type" "R402H16"
			(at 0.064008 -5.517896 180)
			(unlocked yes)
			(layer "F.Fab")
			(hide yes)
			(effects
				(font
					(size 1.016 1.016)
					(thickness 0.1524)
				)
			)
		)
		(duplicate_pad_numbers_are_jumpers no)
		(fp_line
			(start 0.508 -0.9398)
			(end -0.508 -0.9398)
			(stroke
				(width 0.1524)
				(type default)
			)
			(layer "F.SilkS")
		)
		(fp_line
			(start -0.508 -0.9398)
			(end -0.508 0.9398)
			(stroke
				(width 0.1524)
				(type default)
			)
			(layer "F.SilkS")
		)
		(fp_rect
			(start -0.508 0.9398)
			(end 0.508 -0.9398)
			(stroke
				(width 0)
				(type default)
			)
			(fill no)
			(layer "F.CrtYd")
		)
		(fp_rect
			(start -0.508 0.9398)
			(end 0.508 -0.9398)
			(stroke
				(width 0)
				(type default)
			)
			(fill no)
			(layer "F.Fab")
		)
		(pad "1" smd custom
			(at 0 -0.4445 180)
			(size 0.1397 0.1397)
			(layers "F.Cu" "F.Mask" "F.Paste")
			(net "P1V8_C")
			(options
				(clearance outline)
				(anchor circle)
			)
			(primitives
				(gr_poly
					(pts
						(arc
							(start -0.1778 -0.2794)
							(mid -0.249642 -0.249642)
							(end -0.2794 -0.1778)
						)
						(arc
							(start -0.2794 0.1778)
							(mid -0.249642 0.249642)
							(end -0.1778 0.2794)
						)
						(arc
							(start 0.1778 0.2794)
							(mid 0.249642 0.249642)
							(end 0.2794 0.1778)
						)
						(arc
							(start 0.2794 -0.1778)
							(mid 0.249642 -0.249642)
							(end 0.1778 -0.2794)
						)
					)
					(width 0)
					(fill yes)
				)
			)
		)
		(pad "2" smd custom
			(at 0 0.4445 180)
			(size 0.1397 0.1397)
			(layers "F.Cu" "F.Mask" "F.Paste")
			(net "SYS_HALT1#")
			(options
				(clearance outline)
				(anchor circle)
			)
			(primitives
				(gr_poly
					(pts
						(arc
							(start -0.1778 -0.2794)
							(mid -0.249642 -0.249642)
							(end -0.2794 -0.1778)
						)
						(arc
							(start -0.2794 0.1778)
							(mid -0.249642 0.249642)
							(end -0.1778 0.2794)
						)
						(arc
							(start 0.1778 0.2794)
							(mid 0.249642 0.249642)
							(end 0.2794 0.1778)
						)
						(arc
							(start 0.2794 -0.1778)
							(mid 0.249642 -0.249642)
							(end 0.1778 -0.2794)
						)
					)
					(width 0)
					(fill yes)
				)
			)
		)
	)
	(footprint ""
		(layer "F.Cu")
		(at 174.645574 -100.109782)
		(property "Reference" "R492"
			(at 0 0 0)
			(layer "F.SilkS")
			(hide yes)
			(effects
				(font
					(size 1.27 1.27)
				)
			)
		)
		(property "Value" "19K1R2F-GP"
			(at 0.064008 -3.993896 0)
			(unlocked yes)
			(layer "F.Fab")
			(hide yes)
			(effects
				(font
					(size 1.016 1.016)
					(thickness 0.1524)
				)
			)
		)
		(property "Device Type" "R402H16"
			(at 0.064008 -5.517896 0)
			(unlocked yes)
			(layer "F.Fab")
			(hide yes)
			(effects
				(font
					(size 1.016 1.016)
					(thickness 0.1524)
				)
			)
		)
		(duplicate_pad_numbers_are_jumpers no)
		(fp_line
			(start -0.508 -0.9398)
			(end -0.508 0.9398)
			(stroke
				(width 0.1524)
				(type default)
			)
			(layer "F.SilkS")
		)
		(fp_line
			(start 0.508 -0.9398)
			(end -0.508 -0.9398)
			(stroke
				(width 0.1524)
				(type default)
			)
			(layer "F.SilkS")
		)
		(fp_rect
			(start -0.508 0.9398)
			(end 0.508 -0.9398)
			(stroke
				(width 0)
				(type default)
			)
			(fill no)
			(layer "F.CrtYd")
		)
		(fp_rect
			(start -0.508 0.9398)
			(end 0.508 -0.9398)
			(stroke
				(width 0)
				(type default)
			)
			(fill no)
			(layer "F.Fab")
		)
		(pad "1" smd custom
			(at 0 -0.4445)
			(size 0.1397 0.1397)
			(layers "F.Cu" "F.Mask" "F.Paste")
			(net "P0V975")
			(options
				(clearance outline)
				(anchor circle)
			)
			(primitives
				(gr_poly
					(pts
						(arc
							(start -0.1778 -0.2794)
							(mid -0.249642 -0.249642)
							(end -0.2794 -0.1778)
						)
						(arc
							(start -0.2794 0.1778)
							(mid -0.249642 0.249642)
							(end -0.1778 0.2794)
						)
						(arc
							(start 0.1778 0.2794)
							(mid 0.249642 0.249642)
							(end 0.2794 0.1778)
						)
						(arc
							(start 0.2794 -0.1778)
							(mid 0.249642 -0.249642)
							(end 0.1778 -0.2794)
						)
					)
					(width 0)
					(fill yes)
				)
			)
		)
		(pad "2" smd custom
			(at 0 0.4445)
			(size 0.1397 0.1397)
			(layers "F.Cu" "F.Mask" "F.Paste")
			(net "VT235_PGIN")
			(options
				(clearance outline)
				(anchor circle)
			)
			(primitives
				(gr_poly
					(pts
						(arc
							(start -0.1778 -0.2794)
							(mid -0.249642 -0.249642)
							(end -0.2794 -0.1778)
						)
						(arc
							(start -0.2794 0.1778)
							(mid -0.249642 0.249642)
							(end -0.1778 0.2794)
						)
						(arc
							(start 0.1778 0.2794)
							(mid 0.249642 0.249642)
							(end 0.2794 0.1778)
						)
						(arc
							(start 0.2794 -0.1778)
							(mid 0.249642 -0.249642)
							(end 0.1778 -0.2794)
						)
					)
					(width 0)
					(fill yes)
				)
			)
		)
	)
	(footprint ""
		(layer "F.Cu")
		(at 189.2808 -21.9202 -90)
		(property "Reference" "R250"
			(at 0 0 270)
			(layer "F.SilkS")
			(hide yes)
			(effects
				(font
					(size 1.27 1.27)
				)
			)
		)
		(property "Value" "10KR2F-2-GP"
			(at 0.064008 -3.993896 270)
			(unlocked yes)
			(layer "F.Fab")
			(hide yes)
			(effects
				(font
					(size 1.016 1.016)
					(thickness 0.1524)
				)
			)
		)
		(property "Device Type" "R402H16"
			(at 0.064008 -5.517896 270)
			(unlocked yes)
			(layer "F.Fab")
			(hide yes)
			(effects
				(font
					(size 1.016 1.016)
					(thickness 0.1524)
				)
			)
		)
		(duplicate_pad_numbers_are_jumpers no)
		(fp_line
			(start -0.508 -0.9398)
			(end -0.508 0.9398)
			(stroke
				(width 0.1524)
				(type default)
			)
			(layer "F.SilkS")
		)
		(fp_line
			(start 0.508 -0.9398)
			(end -0.508 -0.9398)
			(stroke
				(width 0.1524)
				(type default)
			)
			(layer "F.SilkS")
		)
		(fp_rect
			(start -0.508 0.9398)
			(end 0.508 -0.9398)
			(stroke
				(width 0)
				(type default)
			)
			(fill no)
			(layer "F.CrtYd")
		)
		(fp_rect
			(start -0.508 0.9398)
			(end 0.508 -0.9398)
			(stroke
				(width 0)
				(type default)
			)
			(fill no)
			(layer "F.Fab")
		)
		(pad "1" smd custom
			(at 0 -0.4445 270)
			(size 0.1397 0.1397)
			(layers "F.Cu" "F.Mask" "F.Paste")
			(net "P1V8_C")
			(options
				(clearance outline)
				(anchor circle)
			)
			(primitives
				(gr_poly
					(pts
						(arc
							(start -0.1778 -0.2794)
							(mid -0.249642 -0.249642)
							(end -0.2794 -0.1778)
						)
						(arc
							(start -0.2794 0.1778)
							(mid -0.249642 0.249642)
							(end -0.1778 0.2794)
						)
						(arc
							(start 0.1778 0.2794)
							(mid 0.249642 0.249642)
							(end 0.2794 0.1778)
						)
						(arc
							(start 0.2794 -0.1778)
							(mid 0.249642 -0.249642)
							(end 0.1778 -0.2794)
						)
					)
					(width 0)
					(fill yes)
				)
			)
		)
		(pad "2" smd custom
			(at 0 0.4445 270)
			(size 0.1397 0.1397)
			(layers "F.Cu" "F.Mask" "F.Paste")
			(net "SYS_DBMODE1")
			(options
				(clearance outline)
				(anchor circle)
			)
			(primitives
				(gr_poly
					(pts
						(arc
							(start -0.1778 -0.2794)
							(mid -0.249642 -0.249642)
							(end -0.2794 -0.1778)
						)
						(arc
							(start -0.2794 0.1778)
							(mid -0.249642 0.249642)
							(end -0.1778 0.2794)
						)
						(arc
							(start 0.1778 0.2794)
							(mid 0.249642 0.249642)
							(end 0.2794 0.1778)
						)
						(arc
							(start 0.2794 -0.1778)
							(mid 0.249642 -0.249642)
							(end 0.1778 -0.2794)
						)
					)
					(width 0)
					(fill yes)
				)
			)
		)
	)
	(footprint ""
		(layer "F.Cu")
		(at 147.591526 -40.237664 102)
		(property "Reference" "C336"
			(at 0 0 102)
			(layer "F.SilkS")
			(hide yes)
			(effects
				(font
					(size 1.27 1.27)
				)
			)
		)
		(property "Value" "SCD01U16V1KX-GP"
			(at -2.832296 -1.73983 102)
			(unlocked yes)
			(layer "F.Fab")
			(hide yes)
			(effects
				(font
					(size 1.016 1.016)
					(thickness 0.1524)
				)
			)
		)
		(property "Device Type" "C0201H13"
			(at -2.832174 -3.263834 102)
			(unlocked yes)
			(layer "F.Fab")
			(hide yes)
			(effects
				(font
					(size 1.016 1.016)
					(thickness 0.1524)
				)
			)
		)
		(duplicate_pad_numbers_are_jumpers no)
		(fp_poly
			(pts
				(xy -0.279454 -0.647706) (xy 0.279346 -0.647706) (xy 0.279346 0.647694) (xy -0.279454 0.647694)
			)
			(stroke
				(width 0)
				(type default)
			)
			(fill no)
			(layer "F.CrtYd")
		)
		(fp_poly
			(pts
				(xy -0.279454 -0.647706) (xy 0.279346 -0.647706) (xy 0.279346 0.647694) (xy -0.279454 0.647694)
			)
			(stroke
				(width 0)
				(type default)
			)
			(fill no)
			(layer "F.Fab")
		)
		(pad "1" smd custom
			(at -0.000001 -0.2794 102)
			(size 0.0762 0.0762)
			(layers "F.Cu" "F.Mask" "F.Paste")
			(net "PHY_SCC_TO_IOC_43_DN")
			(options
				(clearance outline)
				(anchor circle)
			)
			(primitives
				(gr_poly
					(pts
						(arc
							(start 0.1524 -0.127)
							(mid 0.137521 -0.162921)
							(end 0.1016 -0.1778)
						)
						(arc
							(start -0.1016 -0.1778)
							(mid -0.137521 -0.162921)
							(end -0.1524 -0.127)
						)
						(arc
							(start -0.1524 0.127)
							(mid -0.137521 0.162921)
							(end -0.1016 0.1778)
						)
						(arc
							(start 0.1016 0.1778)
							(mid 0.137521 0.162921)
							(end 0.1524 0.127)
						)
					)
					(width 0)
					(fill yes)
				)
			)
		)
		(pad "2" smd custom
			(at 0.000001 0.2794 102)
			(size 0.0762 0.0762)
			(layers "F.Cu" "F.Mask" "F.Paste")
			(net "PHY_SCC_TO_IOC_C_43_DN")
			(options
				(clearance outline)
				(anchor circle)
			)
			(primitives
				(gr_poly
					(pts
						(arc
							(start 0.1524 -0.127)
							(mid 0.137521 -0.162921)
							(end 0.1016 -0.1778)
						)
						(arc
							(start -0.1016 -0.1778)
							(mid -0.137521 -0.162921)
							(end -0.1524 -0.127)
						)
						(arc
							(start -0.1524 0.127)
							(mid -0.137521 0.162921)
							(end -0.1016 0.1778)
						)
						(arc
							(start 0.1016 0.1778)
							(mid 0.137521 0.162921)
							(end 0.1524 0.127)
						)
					)
					(width 0)
					(fill yes)
				)
			)
		)
	)
	(footprint ""
		(layer "F.Cu")
		(at 67.3735 -94.6023)
		(property "Reference" "R508"
			(at 0 0 0)
			(layer "F.SilkS")
			(hide yes)
			(effects
				(font
					(size 1.27 1.27)
				)
			)
		)
		(property "Value" "475KR2F-GP"
			(at 0.064008 -3.993896 0)
			(unlocked yes)
			(layer "F.Fab")
			(hide yes)
			(effects
				(font
					(size 1.016 1.016)
					(thickness 0.1524)
				)
			)
		)
		(property "Device Type" "R402H16"
			(at 0.064008 -5.517896 0)
			(unlocked yes)
			(layer "F.Fab")
			(hide yes)
			(effects
				(font
					(size 1.016 1.016)
					(thickness 0.1524)
				)
			)
		)
		(duplicate_pad_numbers_are_jumpers no)
		(fp_line
			(start -0.508 -0.9398)
			(end -0.508 0.9398)
			(stroke
				(width 0.1524)
				(type default)
			)
			(layer "F.SilkS")
		)
		(fp_line
			(start 0.508 -0.9398)
			(end -0.508 -0.9398)
			(stroke
				(width 0.1524)
				(type default)
			)
			(layer "F.SilkS")
		)
		(fp_rect
			(start -0.508 0.9398)
			(end 0.508 -0.9398)
			(stroke
				(width 0)
				(type default)
			)
			(fill no)
			(layer "F.CrtYd")
		)
		(fp_rect
			(start -0.508 0.9398)
			(end 0.508 -0.9398)
			(stroke
				(width 0)
				(type default)
			)
			(fill no)
			(layer "F.Fab")
		)
		(pad "1" smd custom
			(at 0 -0.4445)
			(size 0.1397 0.1397)
			(layers "F.Cu" "F.Mask" "F.Paste")
			(net "P3V3_MODE")
			(options
				(clearance outline)
				(anchor circle)
			)
			(primitives
				(gr_poly
					(pts
						(arc
							(start -0.1778 -0.2794)
							(mid -0.249642 -0.249642)
							(end -0.2794 -0.1778)
						)
						(arc
							(start -0.2794 0.1778)
							(mid -0.249642 0.249642)
							(end -0.1778 0.2794)
						)
						(arc
							(start 0.1778 0.2794)
							(mid 0.249642 0.249642)
							(end 0.2794 0.1778)
						)
						(arc
							(start 0.2794 -0.1778)
							(mid 0.249642 -0.249642)
							(end 0.1778 -0.2794)
						)
					)
					(width 0)
					(fill yes)
				)
			)
		)
		(pad "2" smd custom
			(at 0 0.4445)
			(size 0.1397 0.1397)
			(layers "F.Cu" "F.Mask" "F.Paste")
			(net "SCC_STBY_PGOOD_BUF")
			(options
				(clearance outline)
				(anchor circle)
			)
			(primitives
				(gr_poly
					(pts
						(arc
							(start -0.1778 -0.2794)
							(mid -0.249642 -0.249642)
							(end -0.2794 -0.1778)
						)
						(arc
							(start -0.2794 0.1778)
							(mid -0.249642 0.249642)
							(end -0.1778 0.2794)
						)
						(arc
							(start 0.1778 0.2794)
							(mid 0.249642 0.249642)
							(end 0.2794 0.1778)
						)
						(arc
							(start 0.2794 -0.1778)
							(mid 0.249642 -0.249642)
							(end 0.1778 -0.2794)
						)
					)
					(width 0)
					(fill yes)
				)
			)
		)
	)
)
